(kicad_pcb
	(version 20260206)
	(generator "pcbnew")
	(generator_version "10.0")
	(general
		(thickness 1.6)
		(legacy_teardrops no)
	)
	(paper "A4")
	(title_block
		(title "04192023_DAF0TMB3IC0_F0TG_MB_C_brd_V02_OCP.brd")
		(comment 1 "Grand Teton / footprints 8022-8028 of 8354")
	)
	(layers
		(0 "F.Cu" signal "TOP")
		(4 "In1.Cu" signal "GND")
		(6 "In2.Cu" signal "IN1")
		(8 "In3.Cu" signal "GND1")
		(10 "In4.Cu" signal "IN2")
		(12 "In5.Cu" signal "GND2")
		(14 "In6.Cu" signal "IN3")
		(16 "In7.Cu" signal "GND3")
		(18 "In8.Cu" signal "VCC")
		(20 "In9.Cu" signal "VCC1")
		(22 "In10.Cu" signal "GND4")
		(24 "In11.Cu" signal "IN4")
		(26 "In12.Cu" signal "GND5")
		(28 "In13.Cu" signal "IN5")
		(30 "In14.Cu" signal "GND6")
		(32 "In15.Cu" signal "IN6")
		(34 "In16.Cu" signal "GND7")
		(2 "B.Cu" signal "BOTTOM")
		(9 "F.Adhes" user "F.Adhesive")
		(11 "B.Adhes" user "B.Adhesive")
		(13 "F.Paste" user "Package Geometry/Pastemask Top")
		(15 "B.Paste" user "Package Geometry/Pastemask Bottom")
		(5 "F.SilkS" user "Ref Des/Silkscreen Top")
		(7 "B.SilkS" user "Ref Des/Silkscreen Bottom")
		(1 "F.Mask" user "Board Geometry/Soldermask Top")
		(3 "B.Mask" user "Board Geometry/Soldermask Bottom")
		(17 "Dwgs.User" user "User.Drawings")
		(19 "Cmts.User" user "User.Comments")
		(21 "Eco1.User" user "User.Eco1")
		(23 "Eco2.User" user "User.Eco2")
		(25 "Edge.Cuts" user "Board Geometry/Outline")
		(27 "Margin" user)
		(31 "F.CrtYd" user "Package Geometry/Place Bound Top")
		(29 "B.CrtYd" user "Package Geometry/Place Bound Bottom")
		(35 "F.Fab" user "Ref Des/Assembly Top")
		(33 "B.Fab" user "Ref Des/Assembly Bottom")
	)
	(footprint ""
		(layer "B.Cu")
		(at 388.618476 -396.393162 -90)
		(property "Reference" "C1043"
			(at 0 0 90)
			(layer "B.SilkS")
			(hide yes)
			(effects
				(font
					(size 1.27 1.27)
				)
				(justify mirror)
			)
		)
		(property "Value" ""
			(at 0 0 90)
			(layer "B.Fab")
			(effects
				(font
					(size 1.27 1.27)
				)
				(justify mirror)
			)
		)
		(duplicate_pad_numbers_are_jumpers no)
		(fp_line
			(start -0.299974 0.150114)
			(end 0.299974 0.150114)
			(stroke
				(width 0.1)
				(type default)
			)
			(layer "B.Fab")
		)
		(fp_line
			(start 0.299974 0.150114)
			(end 0.299974 -0.150114)
			(stroke
				(width 0.1)
				(type default)
			)
			(layer "B.Fab")
		)
		(fp_line
			(start -0.299974 -0.150114)
			(end -0.299974 0.150114)
			(stroke
				(width 0.1)
				(type default)
			)
			(layer "B.Fab")
		)
		(fp_line
			(start 0.299974 -0.150114)
			(end -0.299974 -0.150114)
			(stroke
				(width 0.1)
				(type default)
			)
			(layer "B.Fab")
		)
		(pad "1" smd rect
			(at 0.2667 0 90)
			(size 0.3048 0.381)
			(layers "B.Cu" "B.Mask" "B.Paste")
			(net "P0V9_CPU0_RT3_2A")
		)
		(pad "2" smd rect
			(at -0.2667 0 90)
			(size 0.3048 0.381)
			(layers "B.Cu" "B.Mask" "B.Paste")
			(net "GND")
		)
	)
	(footprint ""
		(layer "B.Cu")
		(at 116.078 -417.957 90)
		(property "Reference" "R3525"
			(at 0 0 90)
			(layer "B.SilkS")
			(hide yes)
			(effects
				(font
					(size 1.27 1.27)
				)
				(justify mirror)
			)
		)
		(property "Value" ""
			(at 0 0 90)
			(layer "B.Fab")
			(effects
				(font
					(size 1.27 1.27)
				)
				(justify mirror)
			)
		)
		(duplicate_pad_numbers_are_jumpers no)
		(fp_line
			(start 0.7874 -0.4064)
			(end -0.7874 -0.4064)
			(stroke
				(width 0.1524)
				(type default)
			)
			(layer "B.SilkS")
		)
		(fp_line
			(start -0.7874 -0.4064)
			(end -0.7874 0.4064)
			(stroke
				(width 0.1524)
				(type default)
			)
			(layer "B.SilkS")
		)
		(fp_line
			(start 0.7874 0.4064)
			(end 0.7874 -0.4064)
			(stroke
				(width 0.1524)
				(type default)
			)
			(layer "B.SilkS")
		)
		(fp_line
			(start -0.7874 0.4064)
			(end 0.7874 0.4064)
			(stroke
				(width 0.1524)
				(type default)
			)
			(layer "B.SilkS")
		)
		(fp_line
			(start 0.67945 -0.305054)
			(end 0.12065 -0.305054)
			(stroke
				(width 0.1)
				(type default)
			)
			(layer "B.Fab")
		)
		(fp_line
			(start 0.12065 -0.305054)
			(end 0.12065 -0.2794)
			(stroke
				(width 0.1)
				(type default)
			)
			(layer "B.Fab")
		)
		(fp_line
			(start -0.12065 -0.3048)
			(end -0.67945 -0.3048)
			(stroke
				(width 0.1)
				(type default)
			)
			(layer "B.Fab")
		)
		(fp_line
			(start -0.67945 -0.3048)
			(end -0.67945 0.3048)
			(stroke
				(width 0.1)
				(type default)
			)
			(layer "B.Fab")
		)
		(fp_line
			(start 0.12065 -0.2794)
			(end -0.12065 -0.2794)
			(stroke
				(width 0.1)
				(type default)
			)
			(layer "B.Fab")
		)
		(fp_line
			(start -0.12065 -0.2794)
			(end -0.12065 -0.3048)
			(stroke
				(width 0.1)
				(type default)
			)
			(layer "B.Fab")
		)
		(fp_line
			(start 0.12065 0.2794)
			(end 0.12065 0.3048)
			(stroke
				(width 0.1)
				(type default)
			)
			(layer "B.Fab")
		)
		(fp_line
			(start -0.120396 0.2794)
			(end 0.12065 0.2794)
			(stroke
				(width 0.1)
				(type default)
			)
			(layer "B.Fab")
		)
		(fp_line
			(start 0.67945 0.3048)
			(end 0.67945 -0.305054)
			(stroke
				(width 0.1)
				(type default)
			)
			(layer "B.Fab")
		)
		(fp_line
			(start 0.12065 0.3048)
			(end 0.67945 0.3048)
			(stroke
				(width 0.1)
				(type default)
			)
			(layer "B.Fab")
		)
		(fp_line
			(start -0.120396 0.3048)
			(end -0.120396 0.2794)
			(stroke
				(width 0.1)
				(type default)
			)
			(layer "B.Fab")
		)
		(fp_line
			(start -0.67945 0.3048)
			(end -0.120396 0.3048)
			(stroke
				(width 0.1)
				(type default)
			)
			(layer "B.Fab")
		)
		(pad "1" smd circle
			(at 0.40005 0 270)
			(size 0 0)
			(layers "B.Cu" "B.Mask" "B.Paste")
			(net "P3V3_AUX")
		)
		(pad "2" smd circle
			(at -0.40005 0 270)
			(size 0 0)
			(layers "B.Cu" "B.Mask" "B.Paste")
			(net "GPU_FPGA_EROT_FATALERR_N")
		)
	)
	(footprint ""
		(layer "B.Cu")
		(at 96.706436 -386.766562 90)
		(property "Reference" "C346"
			(at 0 0 90)
			(layer "B.SilkS")
			(hide yes)
			(effects
				(font
					(size 1.27 1.27)
				)
				(justify mirror)
			)
		)
		(property "Value" ""
			(at 0 0 90)
			(layer "B.Fab")
			(effects
				(font
					(size 1.27 1.27)
				)
				(justify mirror)
			)
		)
		(duplicate_pad_numbers_are_jumpers no)
		(fp_line
			(start 0.299974 -0.150114)
			(end -0.299974 -0.150114)
			(stroke
				(width 0.1)
				(type default)
			)
			(layer "B.Fab")
		)
		(fp_line
			(start -0.299974 -0.150114)
			(end -0.299974 0.150114)
			(stroke
				(width 0.1)
				(type default)
			)
			(layer "B.Fab")
		)
		(fp_line
			(start 0.299974 0.150114)
			(end 0.299974 -0.150114)
			(stroke
				(width 0.1)
				(type default)
			)
			(layer "B.Fab")
		)
		(fp_line
			(start -0.299974 0.150114)
			(end 0.299974 0.150114)
			(stroke
				(width 0.1)
				(type default)
			)
			(layer "B.Fab")
		)
		(pad "1" smd rect
			(at 0.2667 0 270)
			(size 0.3048 0.381)
			(layers "B.Cu" "B.Mask" "B.Paste")
			(net "P0V9_CPU1_RT1_2A")
		)
		(pad "2" smd rect
			(at -0.2667 0 270)
			(size 0.3048 0.381)
			(layers "B.Cu" "B.Mask" "B.Paste")
			(net "GND")
		)
	)
	(footprint ""
		(layer "B.Cu")
		(at 52.782978 -428.06493 -90)
		(property "Reference" "R3475"
			(at 0 0 90)
			(layer "B.SilkS")
			(hide yes)
			(effects
				(font
					(size 1.27 1.27)
				)
				(justify mirror)
			)
		)
		(property "Value" ""
			(at 0 0 90)
			(layer "B.Fab")
			(effects
				(font
					(size 1.27 1.27)
				)
				(justify mirror)
			)
		)
		(duplicate_pad_numbers_are_jumpers no)
		(fp_line
			(start -0.7874 0.4064)
			(end 0.7874 0.4064)
			(stroke
				(width 0.1524)
				(type default)
			)
			(layer "B.SilkS")
		)
		(fp_line
			(start 0.7874 0.4064)
			(end 0.7874 -0.4064)
			(stroke
				(width 0.1524)
				(type default)
			)
			(layer "B.SilkS")
		)
		(fp_line
			(start -0.7874 -0.4064)
			(end -0.7874 0.4064)
			(stroke
				(width 0.1524)
				(type default)
			)
			(layer "B.SilkS")
		)
		(fp_line
			(start 0.7874 -0.4064)
			(end -0.7874 -0.4064)
			(stroke
				(width 0.1524)
				(type default)
			)
			(layer "B.SilkS")
		)
		(fp_line
			(start -0.67945 0.3048)
			(end -0.120396 0.3048)
			(stroke
				(width 0.1)
				(type default)
			)
			(layer "B.Fab")
		)
		(fp_line
			(start -0.120396 0.3048)
			(end -0.120396 0.2794)
			(stroke
				(width 0.1)
				(type default)
			)
			(layer "B.Fab")
		)
		(fp_line
			(start 0.12065 0.3048)
			(end 0.67945 0.3048)
			(stroke
				(width 0.1)
				(type default)
			)
			(layer "B.Fab")
		)
		(fp_line
			(start 0.67945 0.3048)
			(end 0.67945 -0.305054)
			(stroke
				(width 0.1)
				(type default)
			)
			(layer "B.Fab")
		)
		(fp_line
			(start -0.120396 0.2794)
			(end 0.12065 0.2794)
			(stroke
				(width 0.1)
				(type default)
			)
			(layer "B.Fab")
		)
		(fp_line
			(start 0.12065 0.2794)
			(end 0.12065 0.3048)
			(stroke
				(width 0.1)
				(type default)
			)
			(layer "B.Fab")
		)
		(fp_line
			(start -0.12065 -0.2794)
			(end -0.12065 -0.3048)
			(stroke
				(width 0.1)
				(type default)
			)
			(layer "B.Fab")
		)
		(fp_line
			(start 0.12065 -0.2794)
			(end -0.12065 -0.2794)
			(stroke
				(width 0.1)
				(type default)
			)
			(layer "B.Fab")
		)
		(fp_line
			(start -0.67945 -0.3048)
			(end -0.67945 0.3048)
			(stroke
				(width 0.1)
				(type default)
			)
			(layer "B.Fab")
		)
		(fp_line
			(start -0.12065 -0.3048)
			(end -0.67945 -0.3048)
			(stroke
				(width 0.1)
				(type default)
			)
			(layer "B.Fab")
		)
		(fp_line
			(start 0.12065 -0.305054)
			(end 0.12065 -0.2794)
			(stroke
				(width 0.1)
				(type default)
			)
			(layer "B.Fab")
		)
		(fp_line
			(start 0.67945 -0.305054)
			(end 0.12065 -0.305054)
			(stroke
				(width 0.1)
				(type default)
			)
			(layer "B.Fab")
		)
		(pad "1" smd circle
			(at 0.40005 0 90)
			(size 0 0)
			(layers "B.Cu" "B.Mask" "B.Paste")
			(net "P3V3_AUX")
		)
		(pad "2" smd circle
			(at -0.40005 0 90)
			(size 0 0)
			(layers "B.Cu" "B.Mask" "B.Paste")
			(net "GPU_PRSNT_N_ISO")
		)
	)
	(footprint ""
		(layer "B.Cu")
		(at 100.478844 -257.930396 180)
		(property "Reference" "C2112"
			(at 0 0 0)
			(layer "B.SilkS")
			(hide yes)
			(effects
				(font
					(size 1.27 1.27)
				)
				(justify mirror)
			)
		)
		(property "Value" ""
			(at 0 0 0)
			(layer "B.Fab")
			(effects
				(font
					(size 1.27 1.27)
				)
				(justify mirror)
			)
		)
		(duplicate_pad_numbers_are_jumpers no)
		(fp_line
			(start 0.7874 0.4064)
			(end 0.7874 -0.4064)
			(stroke
				(width 0.1524)
				(type default)
			)
			(layer "B.SilkS")
		)
		(fp_line
			(start 0.7874 -0.4064)
			(end -0.7874 -0.4064)
			(stroke
				(width 0.1524)
				(type default)
			)
			(layer "B.SilkS")
		)
		(fp_line
			(start -0.7874 0.4064)
			(end 0.7874 0.4064)
			(stroke
				(width 0.1524)
				(type default)
			)
			(layer "B.SilkS")
		)
		(fp_line
			(start -0.7874 -0.4064)
			(end -0.7874 0.4064)
			(stroke
				(width 0.1524)
				(type default)
			)
			(layer "B.SilkS")
		)
		(fp_line
			(start 0.67945 0.3048)
			(end 0.67945 -0.305054)
			(stroke
				(width 0.1)
				(type default)
			)
			(layer "B.Fab")
		)
		(fp_line
			(start 0.67945 -0.305054)
			(end 0.12065 -0.305054)
			(stroke
				(width 0.1)
				(type default)
			)
			(layer "B.Fab")
		)
		(fp_line
			(start 0.12065 0.3048)
			(end 0.67945 0.3048)
			(stroke
				(width 0.1)
				(type default)
			)
			(layer "B.Fab")
		)
		(fp_line
			(start 0.12065 0.2794)
			(end 0.12065 0.3048)
			(stroke
				(width 0.1)
				(type default)
			)
			(layer "B.Fab")
		)
		(fp_line
			(start 0.12065 -0.2794)
			(end -0.12065 -0.2794)
			(stroke
				(width 0.1)
				(type default)
			)
			(layer "B.Fab")
		)
		(fp_line
			(start 0.12065 -0.305054)
			(end 0.12065 -0.2794)
			(stroke
				(width 0.1)
				(type default)
			)
			(layer "B.Fab")
		)
		(fp_line
			(start -0.120396 0.3048)
			(end -0.120396 0.2794)
			(stroke
				(width 0.1)
				(type default)
			)
			(layer "B.Fab")
		)
		(fp_line
			(start -0.120396 0.2794)
			(end 0.12065 0.2794)
			(stroke
				(width 0.1)
				(type default)
			)
			(layer "B.Fab")
		)
		(fp_line
			(start -0.12065 -0.2794)
			(end -0.12065 -0.3048)
			(stroke
				(width 0.1)
				(type default)
			)
			(layer "B.Fab")
		)
		(fp_line
			(start -0.12065 -0.3048)
			(end -0.67945 -0.3048)
			(stroke
				(width 0.1)
				(type default)
			)
			(layer "B.Fab")
		)
		(fp_line
			(start -0.67945 0.3048)
			(end -0.120396 0.3048)
			(stroke
				(width 0.1)
				(type default)
			)
			(layer "B.Fab")
		)
		(fp_line
			(start -0.67945 -0.3048)
			(end -0.67945 0.3048)
			(stroke
				(width 0.1)
				(type default)
			)
			(layer "B.Fab")
		)
		(pad "1" smd circle
			(at 0.40005 0)
			(size 0 0)
			(layers "B.Cu" "B.Mask" "B.Paste")
			(net "PVDDIO_P1")
		)
		(pad "2" smd circle
			(at -0.40005 0)
			(size 0 0)
			(layers "B.Cu" "B.Mask" "B.Paste")
			(net "GND")
		)
	)
	(footprint ""
		(layer "B.Cu")
		(at 123.611386 -254.194564)
		(property "Reference" "C2454"
			(at 0 0 0)
			(layer "B.SilkS")
			(hide yes)
			(effects
				(font
					(size 1.27 1.27)
				)
				(justify mirror)
			)
		)
		(property "Value" ""
			(at 0 0 0)
			(layer "B.Fab")
			(effects
				(font
					(size 1.27 1.27)
				)
				(justify mirror)
			)
		)
		(duplicate_pad_numbers_are_jumpers no)
		(fp_line
			(start -0.7874 -0.4064)
			(end -0.7874 0.4064)
			(stroke
				(width 0.1524)
				(type default)
			)
			(layer "B.SilkS")
		)
		(fp_line
			(start -0.7874 0.4064)
			(end 0.7874 0.4064)
			(stroke
				(width 0.1524)
				(type default)
			)
			(layer "B.SilkS")
		)
		(fp_line
			(start 0.7874 -0.4064)
			(end -0.7874 -0.4064)
			(stroke
				(width 0.1524)
				(type default)
			)
			(layer "B.SilkS")
		)
		(fp_line
			(start 0.7874 0.4064)
			(end 0.7874 -0.4064)
			(stroke
				(width 0.1524)
				(type default)
			)
			(layer "B.SilkS")
		)
		(fp_line
			(start -0.67945 -0.3048)
			(end -0.67945 0.3048)
			(stroke
				(width 0.1)
				(type default)
			)
			(layer "B.Fab")
		)
		(fp_line
			(start -0.67945 0.3048)
			(end -0.120396 0.3048)
			(stroke
				(width 0.1)
				(type default)
			)
			(layer "B.Fab")
		)
		(fp_line
			(start -0.12065 -0.3048)
			(end -0.67945 -0.3048)
			(stroke
				(width 0.1)
				(type default)
			)
			(layer "B.Fab")
		)
		(fp_line
			(start -0.12065 -0.2794)
			(end -0.12065 -0.3048)
			(stroke
				(width 0.1)
				(type default)
			)
			(layer "B.Fab")
		)
		(fp_line
			(start -0.120396 0.2794)
			(end 0.12065 0.2794)
			(stroke
				(width 0.1)
				(type default)
			)
			(layer "B.Fab")
		)
		(fp_line
			(start -0.120396 0.3048)
			(end -0.120396 0.2794)
			(stroke
				(width 0.1)
				(type default)
			)
			(layer "B.Fab")
		)
		(fp_line
			(start 0.12065 -0.305054)
			(end 0.12065 -0.2794)
			(stroke
				(width 0.1)
				(type default)
			)
			(layer "B.Fab")
		)
		(fp_line
			(start 0.12065 -0.2794)
			(end -0.12065 -0.2794)
			(stroke
				(width 0.1)
				(type default)
			)
			(layer "B.Fab")
		)
		(fp_line
			(start 0.12065 0.2794)
			(end 0.12065 0.3048)
			(stroke
				(width 0.1)
				(type default)
			)
			(layer "B.Fab")
		)
		(fp_line
			(start 0.12065 0.3048)
			(end 0.67945 0.3048)
			(stroke
				(width 0.1)
				(type default)
			)
			(layer "B.Fab")
		)
		(fp_line
			(start 0.67945 -0.305054)
			(end 0.12065 -0.305054)
			(stroke
				(width 0.1)
				(type default)
			)
			(layer "B.Fab")
		)
		(fp_line
			(start 0.67945 0.3048)
			(end 0.67945 -0.305054)
			(stroke
				(width 0.1)
				(type default)
			)
			(layer "B.Fab")
		)
		(pad "1" smd circle
			(at 0.40005 0 180)
			(size 0 0)
			(layers "B.Cu" "B.Mask" "B.Paste")
			(net "PVDDCR_SOC_P1")
		)
		(pad "2" smd circle
			(at -0.40005 0 180)
			(size 0 0)
			(layers "B.Cu" "B.Mask" "B.Paste")
			(net "GND")
		)
	)
	(footprint ""
		(layer "B.Cu")
		(at 134.840218 -40.111426)
		(property "Reference" "C6035"
			(at 0 0 0)
			(layer "B.SilkS")
			(hide yes)
			(effects
				(font
					(size 1.27 1.27)
				)
				(justify mirror)
			)
		)
		(property "Value" ""
			(at 0 0 0)
			(layer "B.Fab")
			(effects
				(font
					(size 1.27 1.27)
				)
				(justify mirror)
			)
		)
		(duplicate_pad_numbers_are_jumpers no)
		(fp_line
			(start -0.7874 -0.4064)
			(end -0.7874 0.4064)
			(stroke
				(width 0.1524)
				(type default)
			)
			(layer "B.SilkS")
		)
		(fp_line
			(start -0.7874 0.4064)
			(end 0.7874 0.4064)
			(stroke
				(width 0.1524)
				(type default)
			)
			(layer "B.SilkS")
		)
		(fp_line
			(start 0.7874 -0.4064)
			(end -0.7874 -0.4064)
			(stroke
				(width 0.1524)
				(type default)
			)
			(layer "B.SilkS")
		)
		(fp_line
			(start 0.7874 0.4064)
			(end 0.7874 -0.4064)
			(stroke
				(width 0.1524)
				(type default)
			)
			(layer "B.SilkS")
		)
		(fp_line
			(start -0.67945 -0.3048)
			(end -0.67945 0.3048)
			(stroke
				(width 0.1)
				(type default)
			)
			(layer "B.Fab")
		)
		(fp_line
			(start -0.67945 0.3048)
			(end -0.120396 0.3048)
			(stroke
				(width 0.1)
				(type default)
			)
			(layer "B.Fab")
		)
		(fp_line
			(start -0.12065 -0.3048)
			(end -0.67945 -0.3048)
			(stroke
				(width 0.1)
				(type default)
			)
			(layer "B.Fab")
		)
		(fp_line
			(start -0.12065 -0.2794)
			(end -0.12065 -0.3048)
			(stroke
				(width 0.1)
				(type default)
			)
			(layer "B.Fab")
		)
		(fp_line
			(start -0.120396 0.2794)
			(end 0.12065 0.2794)
			(stroke
				(width 0.1)
				(type default)
			)
			(layer "B.Fab")
		)
		(fp_line
			(start -0.120396 0.3048)
			(end -0.120396 0.2794)
			(stroke
				(width 0.1)
				(type default)
			)
			(layer "B.Fab")
		)
		(fp_line
			(start 0.12065 -0.305054)
			(end 0.12065 -0.2794)
			(stroke
				(width 0.1)
				(type default)
			)
			(layer "B.Fab")
		)
		(fp_line
			(start 0.12065 -0.2794)
			(end -0.12065 -0.2794)
			(stroke
				(width 0.1)
				(type default)
			)
			(layer "B.Fab")
		)
		(fp_line
			(start 0.12065 0.2794)
			(end 0.12065 0.3048)
			(stroke
				(width 0.1)
				(type default)
			)
			(layer "B.Fab")
		)
		(fp_line
			(start 0.12065 0.3048)
			(end 0.67945 0.3048)
			(stroke
				(width 0.1)
				(type default)
			)
			(layer "B.Fab")
		)
		(fp_line
			(start 0.67945 -0.305054)
			(end 0.12065 -0.305054)
			(stroke
				(width 0.1)
				(type default)
			)
			(layer "B.Fab")
		)
		(fp_line
			(start 0.67945 0.3048)
			(end 0.67945 -0.305054)
			(stroke
				(width 0.1)
				(type default)
			)
			(layer "B.Fab")
		)
		(pad "1" smd circle
			(at 0.40005 0 180)
			(size 0 0)
			(layers "B.Cu" "B.Mask" "B.Paste")
			(net "P1V2_CPU0_USB_DVDD12")
		)
		(pad "2" smd circle
			(at -0.40005 0 180)
			(size 0 0)
			(layers "B.Cu" "B.Mask" "B.Paste")
			(net "GND")
		)
	)
)
